#ISCELL
  pure_quanta quanta_title_block_c *
  *
#ISCELL
  standard offpage *
  page211_i1
#CELL
  pure_quanta q_res *
  page211_i10
#ISCELL
  standard offpage *
  page211_i100
#ISCELL
  standard offpage *
  page211_i101
#ISCELL
  standard offpage *
  page211_i102
#ISCELL
  standard offpage *
  page211_i104
#ISCELL
  standard offpage *
  page211_i105
#ISCELL
  standard offpage *
  page211_i108
#ISCELL
  standard offpage *
  page211_i109
#ISCELL
  standard offpage *
  page211_i11
#CELL
  pure_quanta q_res *
  page211_i110
#CELL
  pure_quanta q_res *
  page211_i111
#ISCELL
  standard offpage *
  page211_i116
#ISCELL
  standard offpage *
  page211_i117
#ISCELL
  standard offpage *
  page211_i12
#ISCELL
  standard offpage *
  page211_i120
#ISCELL
  standard offpage *
  page211_i121
#CELL
  pure_quanta q_res *
  page211_i122
#CELL
  pure_quanta q_res *
  page211_i123
#ISCELL
  standard offpage *
  page211_i125
#ISCELL
  standard offpage *
  page211_i126
#CELL
  pure_quanta q_res *
  page211_i127
#ISCELL
  standard offpage *
  page211_i128
#CELL
  pure_quanta q_res *
  page211_i129
#CELL
  pure_quanta q_res *
  page211_i13
#ISCELL
  standard offpage *
  page211_i14
#CELL
  pure_quanta q_res *
  page211_i15
#ISCELL
  standard offpage *
  page211_i16
#ISCELL
  standard offpage *
  page211_i17
#ISCELL
  standard offpage *
  page211_i18
#ISCELL
  standard offpage *
  page211_i19
#ISCELL
  standard offpage *
  page211_i20
#CELL
  pure_quanta q_res *
  page211_i21
#ISCELL
  standard offpage *
  page211_i22
#CELL
  pure_quanta q_res *
  page211_i23
#CELL
  pure_quanta q_res *
  page211_i24
#CELL
  pure_quanta q_res *
  page211_i25
#ISCELL
  standard offpage *
  page211_i26
#ISCELL
  standard offpage *
  page211_i27
#ISCELL
  standard offpage *
  page211_i28
#ISCELL
  standard offpage *
  page211_i3
#ISCELL
  standard offpage *
  page211_i42
#ISCELL
  standard offpage *
  page211_i43
#CELL
  pure_quanta q_res *
  page211_i44
#ISCELL
  standard offpage *
  page211_i45
#ISCELL
  standard offpage *
  page211_i47
#CELL
  pure_quanta q_res *
  page211_i48
#CELL
  pure_quanta q_res *
  page211_i49
#ISCELL
  standard offpage *
  page211_i50
#ISCELL
  standard offpage *
  page211_i51
#ISCELL
  standard offpage *
  page211_i52
#ISCELL
  standard offpage *
  page211_i53
#CELL
  pure_quanta q_res *
  page211_i54
#ISCELL
  standard offpage *
  page211_i6
#CELL
  pure_quanta q_res *
  page211_i62
#ISCELL
  standard offpage *
  page211_i63
#ISCELL
  standard offpage *
  page211_i64
#ISCELL
  standard offpage *
  page211_i66
#ISCELL
  standard offpage *
  page211_i67
#CELL
  pure_quanta q_res *
  page211_i68
#ISCELL
  standard offpage *
  page211_i7
#ISCELL
  standard offpage *
  page211_i77
#ISCELL
  standard offpage *
  page211_i80
#CELL
  pure_quanta q_res *
  page211_i81
#CELL
  pure_quanta q_res *
  page211_i82
#ISCELL
  standard offpage *
  page211_i83
#CELL
  pure_quanta q_res *
  page211_i84
#ISCELL
  standard offpage *
  page211_i85
#ISCELL
  standard offpage *
  page211_i86
#ISCELL
  standard offpage *
  page211_i87
#CELL
  pure_quanta q_res *
  page211_i88
#ISCELL
  standard offpage *
  page211_i89
#CELL
  pure_quanta q_res *
  page211_i9
#ISCELL
  standard offpage *
  page211_i90
#CELL
  pure_quanta q_res *
  page211_i91
#ISCELL
  standard offpage *
  page211_i92
#ISCELL
  standard offpage *
  page211_i93
#ISCELL
  standard offpage *
  page211_i94
#ISCELL
  standard offpage *
  page211_i95
#CELL
  pure_quanta q_res *
  page211_i96
#ISCELL
  standard offpage *
  page211_i97
#CELL
  pure_quanta q_res *
  page211_i98
#CELL
  pure_quanta q_res *
  page211_i99
